POWER AND GROUND LIST - 1  
DESIGNATOR       PART TYPE        GND      P3V3     P3V3_STBY P5V_STBY 
U1B2             PCA9517_SM-IC,G77073-001-GND=GA 4                                   
U1D1             TTL1G126_A_SOT-74HC1G126,IC,A7B 3                 5                 
U1E2             TTL1G08_SOTLF-NC7SZ08,IC,D1032B 3                 5                 
U1L1             TTL3126_QFNLF-74CBTLV3126,IC,DB 7                 14                
                                  15                                  
U1L2             TTL1G86_SOTLF-74AHCT1G86,IC,D3B 3                          5        
U1L3             ADM809_SMLF-IC,D23047-001-GND=A 1                                   
U1L4             TTL1G07_A_SOP-74LVC1G07,IC,C88B 3                 5                 
U1L5             TTL3126_QFNLF-74CBTLV3126,IC,DB 7                 14                
                                  15                                  
U1M1             TTL1G08_SOTLF-NC7SZ08,IC,D1032C 3        5                          
U1M4             74CBTLV1G125_SMLF-IC,C88177-00A 3                 5                 
U1M5             74CBTLV1G125_SMLF-IC,C88177-00A 3                 5                 
U1M6             74CBTLV1G125_SMLF-IC,C88177-00A 3                 5                 
U1R1             TTL1G07_A_SOP-74LVC1G07,IC,C88B 3                 5                 
U1R2             TTL1G126_A_SOT-74HC1G126,IC,A7B 3                 5                 
U2P1             TTL1G07_A_SOP-74LVC1G07,IC,C88B 3                 5                 
U2R1             TTL2G14_SMLF-74LVC2G14,IC,D184B 2                 5                 
U2T2             TTL1G32_A_SOT-74LVC1G32,IC,E60B 3                 5                 
U2T3             TTL1G32_A_SOT-74LVC1G32,IC,E60B 3                 5                 
U3B1             PCA9617_SSOP-IC,G81764-001-GNDA 4                                   
U4G1             PCA9617_SSOP-IC,G81764-001-GNDA 4                                   
U4R1             74CBTLV1G125_SMLF-IC,C88177-00A 3                 5                 
U6F1             PCA9617_SSOP-IC,G81764-001-GNDA 4                                   
U6M1             74CBTLV1G125_SMLF-IC,C88177-00A 3                 5                 
U7D1             74CBTLV1G125_SMLF-IC,C88177-00A 3                 5                 
U7E1             PCA9617_SSOP-IC,G81764-001-GNDA 4                                   
U7E2             TTL1G08_SOTLF-NC7SZ08,IC,D1032B 3                 5                 
U7E3             TTL1G08_SOTLF-NC7SZ08,IC,D1032B 3                 5                 
U8D2             TTL1G07_A_SOP-74LVC1G07,IC,C88B 3                 5                 
U8D3             TTL1G07_A_SOP-74LVC1G07,IC,C88B 3                 5                 
U8D4             AT24C64_SOICLF-IC,C47049-001-GA 4                 8                 
U8D5             TTL1G126_A_SOT-74HC1G126,IC,A7B 3                 5                 
U8E1             TTL08_QFN15-74LVC08A,IC,D90404B 7                 14                
                                  15                                  
U8E2             ADM809_SMLF-IC,D23047-001-GND=A 1                                   
U8E3             TTL1G126_A_SOT-74HC1G126,IC,A7B 3                 5                 
U8E4             TTL1G126_A_SOT-74HC1G126,IC,A7B 3                 5                 
U8F3             TTL2G07_SOT23LF-74LVC2G07,IC,DB 2                 5                 
U8G1             TTL2G07_SOT23LF-74LVC2G07,IC,DB 2                 5                 
U8G2             TTL1G07_A_SOP-74LVC1G07,IC,C88B 3                 5                 
U8G3             TTL1G07_A_SOP-74LVC1G07,IC,C88B 3                 5                 
U9A1             TTL1G07_A_SOP-74LVC1G07,IC,C88B 3                 5                 
U9A3             TTL2G14_SMLF-74LVC2G14,IC,D184B 2                 5                 
U9A4             TTL2G14_SMLF-74LVC2G14,IC,D184B 2                 5                 
U9A5             74CBTLV1G125_SMLF-IC,C88177-00A 3                 5                 
U9F3             TTL1G07_A_SOP-74LVC1G07,IC,C88B 3                 5                 
Y7C1             CRYSTAL_2013-48.000MHZ,IC,D717A 2                                   
                                  4                                   
Y8C1             CRYSTAL_2013-25.000MHZ,IC,H196A 2                                   
                                  4                                   
Y8F1             CRYSTAL_2013LF-25.000MHZ,IC,D7B 2                                   
                                  4                                   
Y9E1             CRYSTAL_2013-25.000MHZ,IC,D717A 2                                   
                                  4                                   
END POWER AND GROUND LIST
